FILE_TYPE = MULTI_PHYS_TABLE;

PART 'CL1001485A'
CLASS=DISCRETE

{========================================================================================}
:CLS_PN             = JEDEC_TYPE | ALT_SYMBOLS | DESCRIPTION                                                 | CPN_STATUS ;
{========================================================================================}
 'CL1001485A'       = 'SOT23_6'  | '(SOT23_6)' | 'DIODE ARRAY, LOW CAPACITANCE TVS, GBE PHY PROTECTION CHIP' | ''        
 'G122-00019-01'    = 'SOT23_6'  | '(SOT23_6)' | 'DIODE ARRAY, LOW CAPACITANCE TVS, GBE PHY PROTECTION CHIP' | 'NFND'        
 'G122-10063-01'    = 'SOT23_6'  | '(SOT23_6)' | 'DIODE ARRAY, LOW CAPACITANCE TVS, GBE PHY PROTECTION CHIP' | ''        

END_PART

END.

